# S9S_MB_2U (Grand Teton) — schematic parts with pin connectivity, parts 1637–1661 of 6093; source: Cadence DE-HDL packaged netlist (pstxprt.dat, pstxnet.dat, pstchip.dat)

J67  PICOPROBE_BXA  DELTA-L 4.0 EMPTY  pkg TRIANG_LAUNCH_3PXB  page 308
  1  \1_p\  POWER  = DELTA_L_85_5INCH_IN3_DP
  2  \2_n\  POWER  = DELTA_L_85_5INCH_IN3_DN
  3  \3_g\  POWER  = DELTA_L_GND_1

J68  PICOPROBE_BXA  DELTA-L 4.0 EMPTY  pkg TRIANG_LAUNCH_3PXB  page 308
  1  \1_p\  POWER  = DELTA_L_85_5INCH_IN4_DP
  2  \2_n\  POWER  = DELTA_L_85_5INCH_IN4_DN
  3  \3_g\  POWER  = DELTA_L_GND_1

J69  PICOPROBE_BXA  DELTA-L 4.0 EMPTY  pkg TRIANG_LAUNCH_3PXB  page 308
  1  \1_p\  POWER  = DELTA_L_85_5INCH_TOP_DN
  2  \2_n\  POWER  = DELTA_L_85_5INCH_TOP_DP
  3  \3_g\  POWER  = DELTA_L_GND_1

J70  PICOPROBE_BXA  DELTA-L 4.0 EMPTY  pkg TRIANG_LAUNCH_3PXB  page 308
  1  \1_p\  POWER  = DELTA_L_85_5INCH_BOT_DN
  2  \2_n\  POWER  = DELTA_L_85_5INCH_BOT_DP
  3  \3_g\  POWER  = DELTA_L_GND_1

J71  PICOPROBE_BXA  DELTA-L 4.0 EMPTY  pkg TRIANG_LAUNCH_3PXB  page 308
  1  \1_p\  POWER  = DELTA_L_85_5INCH_IN1_DN
  2  \2_n\  POWER  = DELTA_L_85_5INCH_IN1_DP
  3  \3_g\  POWER  = DELTA_L_GND_1

J72  PICOPROBE_BXA  DELTA-L 4.0 EMPTY  pkg TRIANG_LAUNCH_3PXB  page 308
  1  \1_p\  POWER  = DELTA_L_85_5INCH_IN2_DN
  2  \2_n\  POWER  = DELTA_L_85_5INCH_IN2_DP
  3  \3_g\  POWER  = DELTA_L_GND_1

J73  PICOPROBE_BXA  DELTA-L 4.0 EMPTY  pkg TRIANG_LAUNCH_3PXB  page 308
  1  \1_p\  POWER  = DELTA_L_85_5INCH_IN3_DN
  2  \2_n\  POWER  = DELTA_L_85_5INCH_IN3_DP
  3  \3_g\  POWER  = DELTA_L_GND_1

J74  PICOPROBE_BXA  DELTA-L 4.0 EMPTY  pkg TRIANG_LAUNCH_3PXB  page 308
  1  \1_p\  POWER  = DELTA_L_85_5INCH_IN4_DN
  2  \2_n\  POWER  = DELTA_L_85_5INCH_IN4_DP
  3  \3_g\  POWER  = DELTA_L_GND_1

J75  PICOPROBE_BXA  DELTA-L 4.0 EMPTY  pkg TRIANG_LAUNCH_3PXB  page 308
  1  \1_p\  POWER  = DELTA_L_85_10INCH_TOP_DP
  2  \2_n\  POWER  = DELTA_L_85_10INCH_TOP_DN
  3  \3_g\  POWER  = DELTA_L_GND_1

J76  PICOPROBE_BXA  DELTA-L 4.0 EMPTY  pkg TRIANG_LAUNCH_3PXB  page 308
  1  \1_p\  POWER  = DELTA_L_85_10INCH_BOT_DP
  2  \2_n\  POWER  = DELTA_L_85_10INCH_BOT_DN
  3  \3_g\  POWER  = DELTA_L_GND_1

J77  PICOPROBE_BXA  DELTA-L 4.0 EMPTY  pkg TRIANG_LAUNCH_3PXB  page 308
  1  \1_p\  POWER  = DELTA_L_85_10INCH_IN1_DP
  2  \2_n\  POWER  = DELTA_L_85_10INCH_IN1_DN
  3  \3_g\  POWER  = DELTA_L_GND_1

J78  PICOPROBE_BXA  DELTA-L 4.0 EMPTY  pkg TRIANG_LAUNCH_3PXB  page 308
  1  \1_p\  POWER  = DELTA_L_85_10INCH_IN2_DP
  2  \2_n\  POWER  = DELTA_L_85_10INCH_IN2_DN
  3  \3_g\  POWER  = DELTA_L_GND_1

J79  PICOPROBE_BXA  DELTA-L 4.0 EMPTY  pkg TRIANG_LAUNCH_3PXB  page 308
  1  \1_p\  POWER  = DELTA_L_85_10INCH_IN3_DP
  2  \2_n\  POWER  = DELTA_L_85_10INCH_IN3_DN
  3  \3_g\  POWER  = DELTA_L_GND_1

J80  PICOPROBE_BXA  DELTA-L 4.0 EMPTY  pkg TRIANG_LAUNCH_3PXB  page 308
  1  \1_p\  POWER  = DELTA_L_85_10INCH_IN4_DP
  2  \2_n\  POWER  = DELTA_L_85_10INCH_IN4_DN
  3  \3_g\  POWER  = DELTA_L_GND_1

J81  PICOPROBE_BXA  DELTA-L 4.0 EMPTY  pkg TRIANG_LAUNCH_3PXB  page 308
  1  \1_p\  POWER  = DELTA_L_85_10INCH_TOP_DN
  2  \2_n\  POWER  = DELTA_L_85_10INCH_TOP_DP
  3  \3_g\  POWER  = DELTA_L_GND_1

J82  PICOPROBE_BXA  DELTA-L 4.0 EMPTY  pkg TRIANG_LAUNCH_3PXB  page 308
  1  \1_p\  POWER  = DELTA_L_85_10INCH_BOT_DN
  2  \2_n\  POWER  = DELTA_L_85_10INCH_BOT_DP
  3  \3_g\  POWER  = DELTA_L_GND_1

J83  PICOPROBE_BXA  DELTA-L 4.0 EMPTY  pkg TRIANG_LAUNCH_3PXB  page 308
  1  \1_p\  POWER  = DELTA_L_85_10INCH_IN1_DN
  2  \2_n\  POWER  = DELTA_L_85_10INCH_IN1_DP
  3  \3_g\  POWER  = DELTA_L_GND_1

J84  PICOPROBE_BXA  DELTA-L 4.0 EMPTY  pkg TRIANG_LAUNCH_3PXB  page 308
  1  \1_p\  POWER  = DELTA_L_85_10INCH_IN2_DN
  2  \2_n\  POWER  = DELTA_L_85_10INCH_IN2_DP
  3  \3_g\  POWER  = DELTA_L_GND_1

J85  PICOPROBE_BXA  DELTA-L 4.0 EMPTY  pkg TRIANG_LAUNCH_3PXB  page 308
  1  \1_p\  POWER  = DELTA_L_85_10INCH_IN3_DN
  2  \2_n\  POWER  = DELTA_L_85_10INCH_IN3_DP
  3  \3_g\  POWER  = DELTA_L_GND_1

J86  PICOPROBE_BXA  DELTA-L 4.0 EMPTY  pkg TRIANG_LAUNCH_3PXB  page 308
  1  \1_p\  POWER  = DELTA_L_85_10INCH_IN4_DN
  2  \2_n\  POWER  = DELTA_L_85_10INCH_IN4_DP
  3  \3_g\  POWER  = DELTA_L_GND_1

J90  SCONN56_123276793  SCONN56_1-2327679-3 IO  pkg CON_F56S2H4D_P0-6W4-6_LUHXA  page 191
  A1  GND_A1  POWER  = GND
  A2  GND_A2  POWER  = GND
  A3  GND_A3  POWER  = GND
  A4  GND_A4  POWER  = GND
  A5  GND_A5  POWER  = GND
  A6  GND_A6  POWER  = GND
  A7  SMBCLK  BI  = SMB_E1S_3V3AUX_ISO_SCL
  A8  SMBDAT  BI  = SMB_E1S_3V3AUX_ISO_SDA
  A9  \smbrst#\  BI  = RST_SMB_E1S_0_N
  A10  \led#_activity\  BI  = E1S_0_LED_ACT_N
  A11  \perst1#_clkreq#\  BI  = E1S_0_PERST1_CLKREQ_N
  A12  \prsnt0#\  BI  = E1S_0_PRSNT_N
  A13  GND_A13  POWER  = GND
  A14  REFCLK_N1  BI  = TP_CLK_100M_E1S_0_DN
  A15  REFCLK_P1  BI  = TP_CLK_100M_E1S_0_DP
  A16  GND_A16  POWER  = GND
  A17  PER_N0  BI  = P3E_PCH_E1S_RX_DP<0>
  A18  PER_P0  BI  = P3E_PCH_E1S_RX_DN<0>
  A19  GND_A19  POWER  = GND
  A20  PER_N1  BI  = P3E_PCH_E1S_RX_DN<1>
  A21  PER_P1  BI  = P3E_PCH_E1S_RX_DP<1>
  A22  GND_A22  POWER  = GND
  A23  PER_N2  BI  = P3E_PCH_E1S_RX_DN<2>
  A24  PER_P2  BI  = P3E_PCH_E1S_RX_DP<2>
  A25  GND_A25  POWER  = GND
  A26  PER_N3  BI  = P3E_PCH_E1S_RX_DN<3>
  A27  PER_P3  BI  = P3E_PCH_E1S_RX_DP<3>
  A28  GND_A28  POWER  = GND
  B1  P12V_B1  POWER  = P12V_E1S_0
  B2  P12V_B2  POWER  = P12V_E1S_0
  B3  P12V_B3  POWER  = P12V_E1S_0
  B4  P12V_B4  POWER  = P12V_E1S_0
  B5  P12V_B5  POWER  = P12V_E1S_0
  B6  P12V_B6  POWER  = P12V_E1S_0
  B7  MFG  BI  = TP_E1S_0_MFG
  B8  RFU  BI  = TP_E1S_0_RFU
  B9  \dualporten#\  BI  = PU_E1S_0_DUALPORT_EN_N
  B10  \perst0#\  BI  = RST_PCIE_PCH_E1S_PERST_N
  B11  P3V3_AUX  POWER  = P3V3_E1S_0
  B12  PWRDIS  BI  = E1S_0_PWRDIS
  B13  GND_B13  POWER  = GND
  B14  REFCLK_N0  BI  = CLK_100M_E1S_0_DN
  B15  REFCLK_P0  BI  = CLK_100M_E1S_0_DP
  B16  GND_B16  POWER  = GND
  B17  PET_N0  BI  = P3E_PCH_E1S_TX_C_DP<0>
  B18  PET_P0  BI  = P3E_PCH_E1S_TX_C_DN<0>
  B19  GND_B19  POWER  = GND
  B20  PET_N1  BI  = P3E_PCH_E1S_TX_C_DP<1>
  B21  PET_P1  BI  = P3E_PCH_E1S_TX_C_DN<1>
  B22  GND_B22  POWER  = GND
  B23  PET_N2  BI  = P3E_PCH_E1S_TX_C_DN<2>
  B24  PET_P2  BI  = P3E_PCH_E1S_TX_C_DP<2>
  B25  GND_B25  POWER  = GND
  B26  PET_N3  BI  = P3E_PCH_E1S_TX_C_DN<3>
  B27  PET_P3  BI  = P3E_PCH_E1S_TX_C_DP<3>
  B28  GND_B28  POWER  = GND
  G1  G1  POWER  = GND
  G2  G2  POWER  = GND

J90_CON  TP  NA  pkg TP_BOM ONLY  page 312 : 1 = NC

J100  SCONN20_513860200CV01  SCONN20_51386-0200C-V01 IO  pkg HEADER2X10SBHXB  page 228
  1  \1\  BI  = SMB_SML0_ME_SCL
  2  \2\  BI  = GND
  3  \3\  BI  = SMB_SML0_ME_SDA
  4  \4\  BI  = IRQ_SML0_ALERT_R1_N
  5  \5\  BI  = SMB_PMBUS_SML1_ME_SCL
  6  \6\  BI  = GND
  7  \7\  BI  = SMB_PMBUS_SML1_ME_SDA
  8  \8\  BI  = IRQ_SML1_PMBUS_ALERT_R_N
  9  \9\  BI  = RST_RSMRST_NM_HDR_N
  10  \10\  BI  = GND
  11  \11\  BI  = SMB_HOST_ME_SCL
  12  \12\  BI  = GND
  13  \13\  BI  = SMB_HOST_ME_SDA
  14  \14\  BI  = NC
  15  \15\  BI  = GND
  16  \16\  BI  = PECI_BMC_ME
  17  \17\  BI  = GND
  18  \18\  BI  = PWRGD_PS_PWROK_ME_CONN
  19  \19\  BI  = FM_BIOS_POST_CMPLT_HDR_N
  20  \20\  BI  = NC

J104  CONN14_210HP207GBR1  CONN14_210-HP2-07GBR1 IO  pkg HEADER2X7XD  page 201
  1  \1\  BI  = PU_ESPI_ENABLE_STRAP
  2  \2\  BI  = JTAG_TRC_PCH_PTI<6>
  3  \3\  BI  = PU_BIOS_RCVR_BOOT
  4  \4\  BI  = FM_PCH_BIOS_RCVR_MODE
  5  \5\  BI  = PU_SWAP_OVERRIDE_N
  6  \6\  BI  = FM_ADR_COMPLETE
  7  \7\  BI  = PD_BIOS_IMAGE_SWAP_N
  8  \8\  BI  = FM_BIOS_IMAGE_SWAP_N
  9  \9\  BI  = PU_FLASH_SECURITY_STRAP
  10  \10\  BI  = FM_FLASH_SECURITY_STRAP
  11  \11\  BI  = PD_ME_RCVR_N
  12  \12\  BI  = FM_ME_RCVR_N
  13  \13\  BI  = PD_PASSWORD_CLEAR
  14  \14\  BI  = FM_PASSWORD_CLEAR_N

J105  CONN112_10137002101LF  CONN112_10137002-101LF IO  pkg HSD_F112D8_P2W1-2_RDH  page 136
  A1  A1  BI  = GPU_3V3IO_RSVD4
  A2  A2  BI  = GND
  A3  A3  BI  = GPU_WP_HW_CTRL_ISO
  A4  A4  BI  = GND
  A5  A5  BI  = GPU_3V3IO_RSVD3
  A6  A6  BI  = GND
  A7  A7  BI  = GPU_3V3IO_RSVD1
  A8  A8  BI  = GND
  B1  B1  BI  = GND
  B2  B2  BI  = P5E_CPU0_PE3_RX_DP<6>
  B3  B3  BI  = GND
  B4  B4  BI  = P5E_CPU0_PE3_RX_DP<4>
  B5  B5  BI  = GND
  B6  B6  BI  = P5E_CPU0_PE3_RX_DN<2>
  B7  B7  BI  = GND
  B8  B8  BI  = P5E_CPU0_PE3_RX_DP<0>
  C1  C1  BI  = P5E_CPU0_PE3_RX_DP<7>
  C2  C2  BI  = P5E_CPU0_PE3_RX_DN<6>
  C3  C3  BI  = P5E_CPU0_PE3_RX_DP<5>
  C4  C4  BI  = P5E_CPU0_PE3_RX_DN<4>
  C5  C5  BI  = P5E_CPU0_PE3_RX_DN<3>
  C6  C6  BI  = P5E_CPU0_PE3_RX_DP<2>
  C7  C7  BI  = P5E_CPU0_PE3_RX_DN<1>
  C8  C8  BI  = P5E_CPU0_PE3_RX_DN<0>
  D1  D1  BI  = P5E_CPU0_PE3_RX_DN<7>
  D2  D2  BI  = GND
  D3  D3  BI  = P5E_CPU0_PE3_RX_DN<5>
  D4  D4  BI  = GND
  D5  D5  BI  = P5E_CPU0_PE3_RX_DP<3>
  D6  D6  BI  = GND
  D7  D7  BI  = P5E_CPU0_PE3_RX_DP<1>
  D8  D8  BI  = GND
  E1  E1  BI  = GND
  E2  E2  BI  = P5E_CPU0_PE2_RX_DP<6>
  E3  E3  BI  = GND
  E4  E4  BI  = P5E_CPU0_PE2_RX_DP<4>
  E5  E5  BI  = GND
  E6  E6  BI  = P5E_CPU0_PE2_RX_DP<2>
  E7  E7  BI  = GND
  E8  E8  BI  = P5E_CPU0_PE2_RX_DP<0>
  F1  F1  BI  = P5E_CPU0_PE2_RX_DP<7>
  F2  F2  BI  = P5E_CPU0_PE2_RX_DN<6>
  F3  F3  BI  = P5E_CPU0_PE2_RX_DP<5>
  F4  F4  BI  = P5E_CPU0_PE2_RX_DN<4>
  F5  F5  BI  = P5E_CPU0_PE2_RX_DP<3>
  F6  F6  BI  = P5E_CPU0_PE2_RX_DN<2>
  F7  F7  BI  = P5E_CPU0_PE2_RX_DP<1>
  F8  F8  BI  = P5E_CPU0_PE2_RX_DN<0>
  G1  G1  BI  = P5E_CPU0_PE2_RX_DN<7>
  G2  G2  BI  = GND
  G3  G3  BI  = P5E_CPU0_PE2_RX_DN<5>
  G4  G4  BI  = GND
  G5  G5  BI  = P5E_CPU0_PE2_RX_DN<3>
  G6  G6  BI  = GND
  G7  G7  BI  = P5E_CPU0_PE2_RX_DN<1>
  G8  G8  BI  = GND
  H1  H1  BI  = GND
  H2  H2  BI  = P5E_CPU0_PE3_TX_C_DN<6>
  H3  H3  BI  = GND
  H4  H4  BI  = P5E_CPU0_PE3_TX_C_DN<4>
  H5  H5  BI  = GND
  H6  H6  BI  = P5E_CPU0_PE3_TX_C_DN<2>
  H7  H7  BI  = GND
  H8  H8  BI  = P5E_CPU0_PE3_TX_C_DP<0>
  I1  I1  BI  = P5E_CPU0_PE3_TX_C_DN<7>
  I2  I2  BI  = P5E_CPU0_PE3_TX_C_DP<6>
  I3  I3  BI  = P5E_CPU0_PE3_TX_C_DN<5>
  I4  I4  BI  = P5E_CPU0_PE3_TX_C_DP<4>
  I5  I5  BI  = P5E_CPU0_PE3_TX_C_DN<3>
  I6  I6  BI  = P5E_CPU0_PE3_TX_C_DP<2>
  I7  I7  BI  = P5E_CPU0_PE3_TX_C_DN<1>
  I8  I8  BI  = P5E_CPU0_PE3_TX_C_DN<0>
  J1  J1  BI  = P5E_CPU0_PE3_TX_C_DP<7>
  J2  J2  BI  = GND
  J3  J3  BI  = P5E_CPU0_PE3_TX_C_DP<5>
  J4  J4  BI  = GND
  J5  J5  BI  = P5E_CPU0_PE3_TX_C_DP<3>
  J6  J6  BI  = GND
  J7  J7  BI  = P5E_CPU0_PE3_TX_C_DP<1>
  J8  J8  BI  = GND
  K1  K1  BI  = GND
  K2  K2  BI  = P5E_CPU0_PE2_TX_C_DP<6>
  K3  K3  BI  = GND
  K4  K4  BI  = P5E_CPU0_PE2_TX_C_DP<4>
  K5  K5  BI  = GND
  K6  K6  BI  = P5E_CPU0_PE2_TX_C_DP<2>
  K7  K7  BI  = GND
  K8  K8  BI  = P5E_CPU0_PE2_TX_C_DP<0>
  L1  L1  BI  = P5E_CPU0_PE2_TX_C_DP<7>
  L2  L2  BI  = P5E_CPU0_PE2_TX_C_DN<6>
  L3  L3  BI  = P5E_CPU0_PE2_TX_C_DP<5>
  L4  L4  BI  = P5E_CPU0_PE2_TX_C_DN<4>
  L5  L5  BI  = P5E_CPU0_PE2_TX_C_DP<3>
  L6  L6  BI  = P5E_CPU0_PE2_TX_C_DN<2>
  L7  L7  BI  = P5E_CPU0_PE2_TX_C_DP<1>
  L8  L8  BI  = P5E_CPU0_PE2_TX_C_DN<0>
  M1  M1  BI  = P5E_CPU0_PE2_TX_C_DN<7>
  M2  M2  BI  = GND
  M3  M3  BI  = P5E_CPU0_PE2_TX_C_DN<5>
  M4  M4  BI  = GND
  M5  M5  BI  = P5E_CPU0_PE2_TX_C_DN<3>
  M6  M6  BI  = GND
  M7  M7  BI  = P5E_CPU0_PE2_TX_C_DN<1>
  M8  M8  BI  = GND
  N1  N1  BI  = GND
  N2  N2  BI  = FM_SWB_PWR_EN_R_BUF
  N3  N3  BI  = GND
  N4  N4  BI  = FM_SWB_BIC_READY_N
  N5  N5  BI  = GND
  N6  N6  BI  = RST_SWB_BIC_BUF_N
  N7  N7  BI  = GND
  N8  N8  BI  = RST_BMC_FROM_SWB_N
